(kicad_pcb
	(version 20260206)
	(generator "pcbnew")
	(generator_version "10.0")
	(general
		(thickness 1.6)
		(legacy_teardrops no)
	)
	(paper "A4")
	(title_block
		(title "12092022_DA0F0TMDCD0_F0T_Management_Board_D_brd_V3_OCP.brd")
		(comment 1 "Grand Teton / footprints 715-720 of 1440")
	)
	(layers
		(0 "F.Cu" signal "TOP")
		(4 "In1.Cu" signal "GND")
		(6 "In2.Cu" signal "IN1")
		(8 "In3.Cu" signal "GND1")
		(10 "In4.Cu" signal "IN2")
		(12 "In5.Cu" signal "VCC")
		(14 "In6.Cu" signal "VCC1")
		(16 "In7.Cu" signal "IN3")
		(18 "In8.Cu" signal "GND2")
		(20 "In9.Cu" signal "IN4")
		(22 "In10.Cu" signal "GND3")
		(2 "B.Cu" signal "BOTTOM")
		(9 "F.Adhes" user "F.Adhesive")
		(11 "B.Adhes" user "B.Adhesive")
		(13 "F.Paste" user "Package Geometry/Pastemask Top")
		(15 "B.Paste" user "Package Geometry/Pastemask Bottom")
		(5 "F.SilkS" user "Ref Des/Silkscreen Top")
		(7 "B.SilkS" user "Ref Des/Silkscreen Bottom")
		(1 "F.Mask" user "Board Geometry/Soldermask Top")
		(3 "B.Mask" user "Board Geometry/Soldermask Bottom")
		(17 "Dwgs.User" user "User.Drawings")
		(19 "Cmts.User" user "User.Comments")
		(21 "Eco1.User" user "User.Eco1")
		(23 "Eco2.User" user "User.Eco2")
		(25 "Edge.Cuts" user "Board Geometry/Outline")
		(27 "Margin" user)
		(31 "F.CrtYd" user "Package Geometry/Place Bound Top")
		(29 "B.CrtYd" user "Package Geometry/Place Bound Bottom")
		(35 "F.Fab" user "Ref Des/Assembly Top")
		(33 "B.Fab" user "Ref Des/Assembly Bottom")
	)
	(footprint ""
		(layer "F.Cu")
		(at 4.318 -80.899 -90)
		(property "Reference" "R388"
			(at 0 0 270)
			(layer "F.SilkS")
			(hide yes)
			(effects
				(font
					(size 1.27 1.27)
				)
			)
		)
		(property "Value" ""
			(at 0 0 270)
			(layer "F.Fab")
			(effects
				(font
					(size 1.27 1.27)
				)
			)
		)
		(duplicate_pad_numbers_are_jumpers no)
		(fp_line
			(start -0.7874 0.4064)
			(end -0.7874 -0.4064)
			(stroke
				(width 0.1524)
				(type default)
			)
			(layer "F.SilkS")
		)
		(fp_line
			(start 0.7874 0.4064)
			(end -0.7874 0.4064)
			(stroke
				(width 0.1524)
				(type default)
			)
			(layer "F.SilkS")
		)
		(fp_line
			(start -0.7874 -0.4064)
			(end 0.7874 -0.4064)
			(stroke
				(width 0.1524)
				(type default)
			)
			(layer "F.SilkS")
		)
		(fp_line
			(start 0.7874 -0.4064)
			(end 0.7874 0.4064)
			(stroke
				(width 0.1524)
				(type default)
			)
			(layer "F.SilkS")
		)
		(fp_line
			(start -0.67945 0.3048)
			(end -0.67945 -0.305054)
			(stroke
				(width 0.1)
				(type default)
			)
			(layer "F.Fab")
		)
		(fp_line
			(start -0.12065 0.3048)
			(end -0.67945 0.3048)
			(stroke
				(width 0.1)
				(type default)
			)
			(layer "F.Fab")
		)
		(fp_line
			(start 0.120396 0.3048)
			(end 0.120396 0.2794)
			(stroke
				(width 0.1)
				(type default)
			)
			(layer "F.Fab")
		)
		(fp_line
			(start 0.67945 0.3048)
			(end 0.120396 0.3048)
			(stroke
				(width 0.1)
				(type default)
			)
			(layer "F.Fab")
		)
		(fp_line
			(start -0.12065 0.2794)
			(end -0.12065 0.3048)
			(stroke
				(width 0.1)
				(type default)
			)
			(layer "F.Fab")
		)
		(fp_line
			(start 0.120396 0.2794)
			(end -0.12065 0.2794)
			(stroke
				(width 0.1)
				(type default)
			)
			(layer "F.Fab")
		)
		(fp_line
			(start -0.12065 -0.2794)
			(end 0.12065 -0.2794)
			(stroke
				(width 0.1)
				(type default)
			)
			(layer "F.Fab")
		)
		(fp_line
			(start 0.12065 -0.2794)
			(end 0.12065 -0.3048)
			(stroke
				(width 0.1)
				(type default)
			)
			(layer "F.Fab")
		)
		(fp_line
			(start 0.12065 -0.3048)
			(end 0.67945 -0.3048)
			(stroke
				(width 0.1)
				(type default)
			)
			(layer "F.Fab")
		)
		(fp_line
			(start 0.67945 -0.3048)
			(end 0.67945 0.3048)
			(stroke
				(width 0.1)
				(type default)
			)
			(layer "F.Fab")
		)
		(fp_line
			(start -0.67945 -0.305054)
			(end -0.12065 -0.305054)
			(stroke
				(width 0.1)
				(type default)
			)
			(layer "F.Fab")
		)
		(fp_line
			(start -0.12065 -0.305054)
			(end -0.12065 -0.2794)
			(stroke
				(width 0.1)
				(type default)
			)
			(layer "F.Fab")
		)
		(pad "1" smd circle
			(at -0.40005 0 270)
			(size 0 0)
			(layers "F.Cu" "F.Mask" "F.Paste")
			(net "RST_SRST_PLD_BMC_R_N")
		)
		(pad "2" smd circle
			(at 0.40005 0 270)
			(size 0 0)
			(layers "F.Cu" "F.Mask" "F.Paste")
			(net "RST_SRST_PLD_BMC_R1_N")
		)
	)
	(footprint ""
		(layer "F.Cu")
		(at 75.057 -21.336 180)
		(property "Reference" "D18"
			(at 1.143 1.11633 0)
			(unlocked yes)
			(layer "F.SilkS")
			(effects
				(font
					(size 0.7874 0.5842)
					(thickness 0.1524)
				)
				(justify left)
			)
		)
		(property "Value" ""
			(at 0 0 180)
			(layer "F.Fab")
			(effects
				(font
					(size 1.27 1.27)
				)
			)
		)
		(duplicate_pad_numbers_are_jumpers no)
		(fp_line
			(start 1.16078 0.4826)
			(end -0.64008 0.4826)
			(stroke
				(width 0.1524)
				(type default)
			)
			(layer "F.SilkS")
		)
		(fp_line
			(start 1.16078 -0.4826)
			(end 1.16078 0.4826)
			(stroke
				(width 0.1524)
				(type default)
			)
			(layer "F.SilkS")
		)
		(fp_line
			(start 1.03378 0.4826)
			(end -0.79248 0.4826)
			(stroke
				(width 0.1524)
				(type default)
			)
			(layer "F.SilkS")
		)
		(fp_line
			(start 1.03378 -0.4826)
			(end 1.03378 0.4826)
			(stroke
				(width 0.1524)
				(type default)
			)
			(layer "F.SilkS")
		)
		(fp_line
			(start 0.90678 0.4826)
			(end -0.90678 0.4826)
			(stroke
				(width 0.1524)
				(type default)
			)
			(layer "F.SilkS")
		)
		(fp_line
			(start 0.90678 -0.4826)
			(end 0.90678 0.4826)
			(stroke
				(width 0.1524)
				(type default)
			)
			(layer "F.SilkS")
		)
		(fp_line
			(start -0.64008 -0.4826)
			(end 1.16078 -0.4826)
			(stroke
				(width 0.1524)
				(type default)
			)
			(layer "F.SilkS")
		)
		(fp_line
			(start -0.79248 -0.4826)
			(end 1.03378 -0.4826)
			(stroke
				(width 0.1524)
				(type default)
			)
			(layer "F.SilkS")
		)
		(fp_line
			(start -0.89408 -0.4826)
			(end 0.90678 -0.4826)
			(stroke
				(width 0.1524)
				(type default)
			)
			(layer "F.SilkS")
		)
		(fp_line
			(start -0.90678 0.4826)
			(end -0.90678 -0.4699)
			(stroke
				(width 0.1524)
				(type default)
			)
			(layer "F.SilkS")
		)
		(fp_line
			(start 0.499872 0.249936)
			(end -0.499872 0.249936)
			(stroke
				(width 0.1)
				(type default)
			)
			(layer "F.Fab")
		)
		(fp_line
			(start 0.499872 -0.249936)
			(end 0.499872 0.249936)
			(stroke
				(width 0.1)
				(type default)
			)
			(layer "F.Fab")
		)
		(fp_line
			(start -0.499872 0.249936)
			(end -0.499872 -0.249936)
			(stroke
				(width 0.1)
				(type default)
			)
			(layer "F.Fab")
		)
		(fp_line
			(start -0.499872 -0.249936)
			(end 0.499872 -0.249936)
			(stroke
				(width 0.1)
				(type default)
			)
			(layer "F.Fab")
		)
		(pad "A" smd rect
			(at -0.47498 0 180)
			(size 0.6096 0.7112)
			(layers "F.Cu" "F.Mask" "F.Paste")
			(net "P3V3_AUX")
		)
		(pad "C" smd rect
			(at 0.47498 0 180)
			(size 0.6096 0.7112)
			(layers "F.Cu" "F.Mask" "F.Paste")
			(net "FM_UARTSW_LSB_R1_N")
		)
	)
	(footprint ""
		(layer "F.Cu")
		(at 27.559 -10.287 -90)
		(property "Reference" "R813"
			(at 0 0 270)
			(layer "F.SilkS")
			(hide yes)
			(effects
				(font
					(size 1.27 1.27)
				)
			)
		)
		(property "Value" ""
			(at 0 0 270)
			(layer "F.Fab")
			(effects
				(font
					(size 1.27 1.27)
				)
			)
		)
		(duplicate_pad_numbers_are_jumpers no)
		(fp_line
			(start -0.7874 0.4064)
			(end -0.7874 -0.4064)
			(stroke
				(width 0.1524)
				(type default)
			)
			(layer "F.SilkS")
		)
		(fp_line
			(start 0.7874 0.4064)
			(end -0.7874 0.4064)
			(stroke
				(width 0.1524)
				(type default)
			)
			(layer "F.SilkS")
		)
		(fp_line
			(start -0.7874 -0.4064)
			(end 0.7874 -0.4064)
			(stroke
				(width 0.1524)
				(type default)
			)
			(layer "F.SilkS")
		)
		(fp_line
			(start 0.7874 -0.4064)
			(end 0.7874 0.4064)
			(stroke
				(width 0.1524)
				(type default)
			)
			(layer "F.SilkS")
		)
		(fp_line
			(start -0.67945 0.3048)
			(end -0.67945 -0.305054)
			(stroke
				(width 0.1)
				(type default)
			)
			(layer "F.Fab")
		)
		(fp_line
			(start -0.12065 0.3048)
			(end -0.67945 0.3048)
			(stroke
				(width 0.1)
				(type default)
			)
			(layer "F.Fab")
		)
		(fp_line
			(start 0.120396 0.3048)
			(end 0.120396 0.2794)
			(stroke
				(width 0.1)
				(type default)
			)
			(layer "F.Fab")
		)
		(fp_line
			(start 0.67945 0.3048)
			(end 0.120396 0.3048)
			(stroke
				(width 0.1)
				(type default)
			)
			(layer "F.Fab")
		)
		(fp_line
			(start -0.12065 0.2794)
			(end -0.12065 0.3048)
			(stroke
				(width 0.1)
				(type default)
			)
			(layer "F.Fab")
		)
		(fp_line
			(start 0.120396 0.2794)
			(end -0.12065 0.2794)
			(stroke
				(width 0.1)
				(type default)
			)
			(layer "F.Fab")
		)
		(fp_line
			(start -0.12065 -0.2794)
			(end 0.12065 -0.2794)
			(stroke
				(width 0.1)
				(type default)
			)
			(layer "F.Fab")
		)
		(fp_line
			(start 0.12065 -0.2794)
			(end 0.12065 -0.3048)
			(stroke
				(width 0.1)
				(type default)
			)
			(layer "F.Fab")
		)
		(fp_line
			(start 0.12065 -0.3048)
			(end 0.67945 -0.3048)
			(stroke
				(width 0.1)
				(type default)
			)
			(layer "F.Fab")
		)
		(fp_line
			(start 0.67945 -0.3048)
			(end 0.67945 0.3048)
			(stroke
				(width 0.1)
				(type default)
			)
			(layer "F.Fab")
		)
		(fp_line
			(start -0.67945 -0.305054)
			(end -0.12065 -0.305054)
			(stroke
				(width 0.1)
				(type default)
			)
			(layer "F.Fab")
		)
		(fp_line
			(start -0.12065 -0.305054)
			(end -0.12065 -0.2794)
			(stroke
				(width 0.1)
				(type default)
			)
			(layer "F.Fab")
		)
		(pad "1" smd circle
			(at -0.40005 0 270)
			(size 0 0)
			(layers "F.Cu" "F.Mask" "F.Paste")
			(net "HDD_LED_BUF")
		)
		(pad "2" smd circle
			(at 0.40005 0 270)
			(size 0 0)
			(layers "F.Cu" "F.Mask" "F.Paste")
			(net "HDD_LED_BUF_R")
		)
	)
	(footprint ""
		(layer "F.Cu")
		(at 21.463 -102.743 -90)
		(property "Reference" "R747"
			(at 0 0 270)
			(layer "F.SilkS")
			(hide yes)
			(effects
				(font
					(size 1.27 1.27)
				)
			)
		)
		(property "Value" ""
			(at 0 0 270)
			(layer "F.Fab")
			(effects
				(font
					(size 1.27 1.27)
				)
			)
		)
		(duplicate_pad_numbers_are_jumpers no)
		(fp_line
			(start -0.7874 0.4064)
			(end -0.7874 -0.4064)
			(stroke
				(width 0.1524)
				(type default)
			)
			(layer "F.SilkS")
		)
		(fp_line
			(start 0.7874 0.4064)
			(end -0.7874 0.4064)
			(stroke
				(width 0.1524)
				(type default)
			)
			(layer "F.SilkS")
		)
		(fp_line
			(start -0.7874 -0.4064)
			(end 0.7874 -0.4064)
			(stroke
				(width 0.1524)
				(type default)
			)
			(layer "F.SilkS")
		)
		(fp_line
			(start 0.7874 -0.4064)
			(end 0.7874 0.4064)
			(stroke
				(width 0.1524)
				(type default)
			)
			(layer "F.SilkS")
		)
		(fp_line
			(start -0.67945 0.3048)
			(end -0.67945 -0.305054)
			(stroke
				(width 0.1)
				(type default)
			)
			(layer "F.Fab")
		)
		(fp_line
			(start -0.12065 0.3048)
			(end -0.67945 0.3048)
			(stroke
				(width 0.1)
				(type default)
			)
			(layer "F.Fab")
		)
		(fp_line
			(start 0.120396 0.3048)
			(end 0.120396 0.2794)
			(stroke
				(width 0.1)
				(type default)
			)
			(layer "F.Fab")
		)
		(fp_line
			(start 0.67945 0.3048)
			(end 0.120396 0.3048)
			(stroke
				(width 0.1)
				(type default)
			)
			(layer "F.Fab")
		)
		(fp_line
			(start -0.12065 0.2794)
			(end -0.12065 0.3048)
			(stroke
				(width 0.1)
				(type default)
			)
			(layer "F.Fab")
		)
		(fp_line
			(start 0.120396 0.2794)
			(end -0.12065 0.2794)
			(stroke
				(width 0.1)
				(type default)
			)
			(layer "F.Fab")
		)
		(fp_line
			(start -0.12065 -0.2794)
			(end 0.12065 -0.2794)
			(stroke
				(width 0.1)
				(type default)
			)
			(layer "F.Fab")
		)
		(fp_line
			(start 0.12065 -0.2794)
			(end 0.12065 -0.3048)
			(stroke
				(width 0.1)
				(type default)
			)
			(layer "F.Fab")
		)
		(fp_line
			(start 0.12065 -0.3048)
			(end 0.67945 -0.3048)
			(stroke
				(width 0.1)
				(type default)
			)
			(layer "F.Fab")
		)
		(fp_line
			(start 0.67945 -0.3048)
			(end 0.67945 0.3048)
			(stroke
				(width 0.1)
				(type default)
			)
			(layer "F.Fab")
		)
		(fp_line
			(start -0.67945 -0.305054)
			(end -0.12065 -0.305054)
			(stroke
				(width 0.1)
				(type default)
			)
			(layer "F.Fab")
		)
		(fp_line
			(start -0.12065 -0.305054)
			(end -0.12065 -0.2794)
			(stroke
				(width 0.1)
				(type default)
			)
			(layer "F.Fab")
		)
		(pad "1" smd circle
			(at -0.40005 0 270)
			(size 0 0)
			(layers "F.Cu" "F.Mask" "F.Paste")
			(net "FM_BMC_CRASHLOG_TRIG_N")
		)
		(pad "2" smd circle
			(at 0.40005 0 270)
			(size 0 0)
			(layers "F.Cu" "F.Mask" "F.Paste")
			(net "FM_BMC_CRASHLOG_TRIG_R2_N")
		)
	)
	(footprint ""
		(layer "F.Cu")
		(at 43.6626 -34.6456 -90)
		(property "Reference" "R112"
			(at 0 0 270)
			(layer "F.SilkS")
			(hide yes)
			(effects
				(font
					(size 1.27 1.27)
				)
			)
		)
		(property "Value" ""
			(at 0 0 270)
			(layer "F.Fab")
			(effects
				(font
					(size 1.27 1.27)
				)
			)
		)
		(duplicate_pad_numbers_are_jumpers no)
		(fp_line
			(start -0.7874 0.4064)
			(end -0.7874 -0.4064)
			(stroke
				(width 0.1524)
				(type default)
			)
			(layer "F.SilkS")
		)
		(fp_line
			(start 0.7874 0.4064)
			(end -0.7874 0.4064)
			(stroke
				(width 0.1524)
				(type default)
			)
			(layer "F.SilkS")
		)
		(fp_line
			(start -0.7874 -0.4064)
			(end 0.7874 -0.4064)
			(stroke
				(width 0.1524)
				(type default)
			)
			(layer "F.SilkS")
		)
		(fp_line
			(start 0.7874 -0.4064)
			(end 0.7874 0.4064)
			(stroke
				(width 0.1524)
				(type default)
			)
			(layer "F.SilkS")
		)
		(fp_line
			(start -0.67945 0.3048)
			(end -0.67945 -0.305054)
			(stroke
				(width 0.1)
				(type default)
			)
			(layer "F.Fab")
		)
		(fp_line
			(start -0.12065 0.3048)
			(end -0.67945 0.3048)
			(stroke
				(width 0.1)
				(type default)
			)
			(layer "F.Fab")
		)
		(fp_line
			(start 0.120396 0.3048)
			(end 0.120396 0.2794)
			(stroke
				(width 0.1)
				(type default)
			)
			(layer "F.Fab")
		)
		(fp_line
			(start 0.67945 0.3048)
			(end 0.120396 0.3048)
			(stroke
				(width 0.1)
				(type default)
			)
			(layer "F.Fab")
		)
		(fp_line
			(start -0.12065 0.2794)
			(end -0.12065 0.3048)
			(stroke
				(width 0.1)
				(type default)
			)
			(layer "F.Fab")
		)
		(fp_line
			(start 0.120396 0.2794)
			(end -0.12065 0.2794)
			(stroke
				(width 0.1)
				(type default)
			)
			(layer "F.Fab")
		)
		(fp_line
			(start -0.12065 -0.2794)
			(end 0.12065 -0.2794)
			(stroke
				(width 0.1)
				(type default)
			)
			(layer "F.Fab")
		)
		(fp_line
			(start 0.12065 -0.2794)
			(end 0.12065 -0.3048)
			(stroke
				(width 0.1)
				(type default)
			)
			(layer "F.Fab")
		)
		(fp_line
			(start 0.12065 -0.3048)
			(end 0.67945 -0.3048)
			(stroke
				(width 0.1)
				(type default)
			)
			(layer "F.Fab")
		)
		(fp_line
			(start 0.67945 -0.3048)
			(end 0.67945 0.3048)
			(stroke
				(width 0.1)
				(type default)
			)
			(layer "F.Fab")
		)
		(fp_line
			(start -0.67945 -0.305054)
			(end -0.12065 -0.305054)
			(stroke
				(width 0.1)
				(type default)
			)
			(layer "F.Fab")
		)
		(fp_line
			(start -0.12065 -0.305054)
			(end -0.12065 -0.2794)
			(stroke
				(width 0.1)
				(type default)
			)
			(layer "F.Fab")
		)
		(pad "1" smd circle
			(at -0.40005 0 270)
			(size 0 0)
			(layers "F.Cu" "F.Mask" "F.Paste")
			(net "FM_BIOS_DEBUG_EN_R_N")
		)
		(pad "2" smd circle
			(at 0.40005 0 270)
			(size 0 0)
			(layers "F.Cu" "F.Mask" "F.Paste")
			(net "FM_BIOS_DEBUG_EN_N")
		)
	)
	(footprint ""
		(layer "F.Cu")
		(at 77.55128 -59.065922 -90)
		(property "Reference" "PC259"
			(at 0 0 270)
			(layer "F.SilkS")
			(hide yes)
			(effects
				(font
					(size 1.27 1.27)
				)
			)
		)
		(property "Value" ""
			(at 0 0 270)
			(layer "F.Fab")
			(effects
				(font
					(size 1.27 1.27)
				)
			)
		)
		(duplicate_pad_numbers_are_jumpers no)
		(fp_line
			(start -1.651 0.8382)
			(end -1.651 -0.8382)
			(stroke
				(width 0.1524)
				(type default)
			)
			(layer "F.SilkS")
		)
		(fp_line
			(start 0 0.8382)
			(end 0 -0.8382)
			(stroke
				(width 0.1524)
				(type default)
			)
			(layer "F.SilkS")
		)
		(fp_line
			(start 1.651 0.8382)
			(end -1.651 0.8382)
			(stroke
				(width 0.1524)
				(type default)
			)
			(layer "F.SilkS")
		)
		(fp_line
			(start -1.651 -0.8382)
			(end 1.651 -0.8382)
			(stroke
				(width 0.1524)
				(type default)
			)
			(layer "F.SilkS")
		)
		(fp_line
			(start 1.651 -0.8382)
			(end 1.651 0.8382)
			(stroke
				(width 0.1524)
				(type default)
			)
			(layer "F.SilkS")
		)
		(fp_line
			(start -1.55956 0.7366)
			(end -1.524 0.7366)
			(stroke
				(width 0.1)
				(type default)
			)
			(layer "F.Fab")
		)
		(fp_line
			(start -1.524 0.7366)
			(end 1.524 0.7366)
			(stroke
				(width 0.1)
				(type default)
			)
			(layer "F.Fab")
		)
		(fp_line
			(start 1.524 0.7366)
			(end 1.55956 0.7366)
			(stroke
				(width 0.1)
				(type default)
			)
			(layer "F.Fab")
		)
		(fp_line
			(start 1.55956 0.7366)
			(end 1.55956 -0.7366)
			(stroke
				(width 0.1)
				(type default)
			)
			(layer "F.Fab")
		)
		(fp_line
			(start -1.55956 -0.7366)
			(end -1.55956 0.7366)
			(stroke
				(width 0.1)
				(type default)
			)
			(layer "F.Fab")
		)
		(fp_line
			(start -1.524 -0.7366)
			(end -1.55956 -0.7366)
			(stroke
				(width 0.1)
				(type default)
			)
			(layer "F.Fab")
		)
		(fp_line
			(start 1.524 -0.7366)
			(end -1.524 -0.7366)
			(stroke
				(width 0.1)
				(type default)
			)
			(layer "F.Fab")
		)
		(fp_line
			(start 1.55956 -0.7366)
			(end 1.524 -0.7366)
			(stroke
				(width 0.1)
				(type default)
			)
			(layer "F.Fab")
		)
		(pad "1" smd rect
			(at -0.94996 0 90)
			(size 1.1176 1.3716)
			(layers "F.Cu" "F.Mask" "F.Paste")
			(net "P1V2_AUX")
		)
		(pad "2" smd rect
			(at 0.94996 0 90)
			(size 1.1176 1.3716)
			(layers "F.Cu" "F.Mask" "F.Paste")
			(net "GND")
		)
	)
)
